# SCM (Grand Teton) — schematic netlist excerpt (pin names and nets, part order shuffled) for the footprints in the layout excerpt that follows; sources: Cadence DE-HDL packaged netlist, KiCad conversion of 12092022_DA0F0TMDCD0_F0T_Management_Board_D_brd_V3_OCP.brd

R145  Q_RES  10K 1% CHIP  pkg 0402LF  page 27 : A = P3V3_AUX ; B = SMB_BMC_MM12_SCL

(kicad_pcb
	(version 20260206)
	(generator "pcbnew")
	(generator_version "10.0")
	(general
		(thickness 1.6)
		(legacy_teardrops no)
	)
	(paper "A4")
	(title_block
		(title "12092022_DA0F0TMDCD0_F0T_Management_Board_D_brd_V3_OCP.brd")
		(comment 1 "Grand Teton / footprints 264-264 of 1440")
	)
	(layers
		(0 "F.Cu" signal "TOP")
		(4 "In1.Cu" signal "GND")
		(6 "In2.Cu" signal "IN1")
		(8 "In3.Cu" signal "GND1")
		(10 "In4.Cu" signal "IN2")
		(12 "In5.Cu" signal "VCC")
		(14 "In6.Cu" signal "VCC1")
		(16 "In7.Cu" signal "IN3")
		(18 "In8.Cu" signal "GND2")
		(20 "In9.Cu" signal "IN4")
		(22 "In10.Cu" signal "GND3")
		(2 "B.Cu" signal "BOTTOM")
		(9 "F.Adhes" user "F.Adhesive")
		(11 "B.Adhes" user "B.Adhesive")
		(13 "F.Paste" user "Package Geometry/Pastemask Top")
		(15 "B.Paste" user "Package Geometry/Pastemask Bottom")
		(5 "F.SilkS" user "Ref Des/Silkscreen Top")
		(7 "B.SilkS" user "Ref Des/Silkscreen Bottom")
		(1 "F.Mask" user "Board Geometry/Soldermask Top")
		(3 "B.Mask" user "Board Geometry/Soldermask Bottom")
		(17 "Dwgs.User" user "User.Drawings")
		(19 "Cmts.User" user "User.Comments")
		(21 "Eco1.User" user "User.Eco1")
		(23 "Eco2.User" user "User.Eco2")
		(25 "Edge.Cuts" user "Board Geometry/Outline")
		(27 "Margin" user)
		(31 "F.CrtYd" user "Package Geometry/Place Bound Top")
		(29 "B.CrtYd" user "Package Geometry/Place Bound Bottom")
		(35 "F.Fab" user "Ref Des/Assembly Top")
		(33 "B.Fab" user "Ref Des/Assembly Bottom")
	)
	(footprint ""
		(layer "F.Cu")
		(at 37.865304 -47.587916)
		(property "Reference" "R145"
			(at 0 0 0)
			(layer "F.SilkS")
			(hide yes)
			(effects
				(font
					(size 1.27 1.27)
				)
			)
		)
		(property "Value" ""
			(at 0 0 0)
			(layer "F.Fab")
			(effects
				(font
					(size 1.27 1.27)
				)
			)
		)
		(duplicate_pad_numbers_are_jumpers no)
		(fp_line
			(start -0.7874 -0.4064)
			(end 0.7874 -0.4064)
			(stroke
				(width 0.1524)
				(type default)
			)
			(layer "F.SilkS")
		)
		(fp_line
			(start -0.7874 0.4064)
			(end -0.7874 -0.4064)
			(stroke
				(width 0.1524)
				(type default)
			)
			(layer "F.SilkS")
		)
		(fp_line
			(start 0.7874 -0.4064)
			(end 0.7874 0.4064)
			(stroke
				(width 0.1524)
				(type default)
			)
			(layer "F.SilkS")
		)
		(fp_line
			(start 0.7874 0.4064)
			(end -0.7874 0.4064)
			(stroke
				(width 0.1524)
				(type default)
			)
			(layer "F.SilkS")
		)
		(fp_line
			(start -0.67945 -0.305054)
			(end -0.12065 -0.305054)
			(stroke
				(width 0.1)
				(type default)
			)
			(layer "F.Fab")
		)
		(fp_line
			(start -0.67945 0.3048)
			(end -0.67945 -0.305054)
			(stroke
				(width 0.1)
				(type default)
			)
			(layer "F.Fab")
		)
		(fp_line
			(start -0.12065 -0.305054)
			(end -0.12065 -0.2794)
			(stroke
				(width 0.1)
				(type default)
			)
			(layer "F.Fab")
		)
		(fp_line
			(start -0.12065 -0.2794)
			(end 0.12065 -0.2794)
			(stroke
				(width 0.1)
				(type default)
			)
			(layer "F.Fab")
		)
		(fp_line
			(start -0.12065 0.2794)
			(end -0.12065 0.3048)
			(stroke
				(width 0.1)
				(type default)
			)
			(layer "F.Fab")
		)
		(fp_line
			(start -0.12065 0.3048)
			(end -0.67945 0.3048)
			(stroke
				(width 0.1)
				(type default)
			)
			(layer "F.Fab")
		)
		(fp_line
			(start 0.120396 0.2794)
			(end -0.12065 0.2794)
			(stroke
				(width 0.1)
				(type default)
			)
			(layer "F.Fab")
		)
		(fp_line
			(start 0.120396 0.3048)
			(end 0.120396 0.2794)
			(stroke
				(width 0.1)
				(type default)
			)
			(layer "F.Fab")
		)
		(fp_line
			(start 0.12065 -0.3048)
			(end 0.67945 -0.3048)
			(stroke
				(width 0.1)
				(type default)
			)
			(layer "F.Fab")
		)
		(fp_line
			(start 0.12065 -0.2794)
			(end 0.12065 -0.3048)
			(stroke
				(width 0.1)
				(type default)
			)
			(layer "F.Fab")
		)
		(fp_line
			(start 0.67945 -0.3048)
			(end 0.67945 0.3048)
			(stroke
				(width 0.1)
				(type default)
			)
			(layer "F.Fab")
		)
		(fp_line
			(start 0.67945 0.3048)
			(end 0.120396 0.3048)
			(stroke
				(width 0.1)
				(type default)
			)
			(layer "F.Fab")
		)
		(pad "1" smd circle
			(at -0.40005 0)
			(size 0 0)
			(layers "F.Cu" "F.Mask" "F.Paste")
			(net "P3V3_AUX")
		)
		(pad "2" smd circle
			(at 0.40005 0)
			(size 0 0)
			(layers "F.Cu" "F.Mask" "F.Paste")
			(net "SMB_BMC_MM12_SCL")
		)
	)
)
